# T6G (Grand Teton) — schematic netlist excerpt (pin names and nets, part order shuffled) for the footprints in the layout excerpt that follows; sources: Cadence DE-HDL packaged netlist, KiCad conversion of 04192023_DAF0TMB3IC0_F0TG_MB_C_brd_V02_OCP.brd

PU11  ISL99390FRZTR5935  ISL99390FRZ-TR5935 IC  pkg QFN21_6X5XB  page 203
  VOS  = PVDDCR_CPU1_P0_VOS6
  AGND  = GND
  VCC  = PVDDCR_CPU1_P0_VCC6
  PVCC  = PVDDCR_CPU1_P0_PVCC
  PGND1  = GND
  GL1  = NC_PVDDCR_CPU1_P0_GL1_6
  PGND2  = GND
  SW  = SW_PVDDCR_CPU1_P0_SW6
  VIN1  = SW_P12V_AUX_PVDDCR_CPU1_P0_FLT
  VIN2  = SW_P12V_AUX_PVDDCR_CPU1_P0_FLT
  DNC  = NC_PVDDCR_CPU1_P0_DNC6
  PHASE  = SW_PVDDCR_CPU1_P0_BOOTR6
  BOOT  = SW_PVDDCR_CPU1_P0_BOOT6
  PWM  = PVDDCR_CPU1_P0_PWM6
  EN  = PVDDCR_CPU1_P0_VCC6
  TOUT_FLT  = PVDDCR_CPU1_P0_TEMP0
  LSET  = PVDDCR_CPU1_P0_LSET6
  IOUT  = PVDDCR_CPU1_P0_IMON6
  REFIN  = PVDDCR_CPU1_P0_VCCS
  PGND3  = GND
  GL2  = NC_PVDDCR_CPU1_P0_GL2_6

(kicad_pcb
	(version 20260206)
	(generator "pcbnew")
	(generator_version "10.0")
	(general
		(thickness 1.6)
		(legacy_teardrops no)
	)
	(paper "A4")
	(title_block
		(title "04192023_DAF0TMB3IC0_F0TG_MB_C_brd_V02_OCP.brd")
		(comment 1 "Grand Teton / footprints 671-671 of 8354")
	)
	(layers
		(0 "F.Cu" signal "TOP")
		(4 "In1.Cu" signal "GND")
		(6 "In2.Cu" signal "IN1")
		(8 "In3.Cu" signal "GND1")
		(10 "In4.Cu" signal "IN2")
		(12 "In5.Cu" signal "GND2")
		(14 "In6.Cu" signal "IN3")
		(16 "In7.Cu" signal "GND3")
		(18 "In8.Cu" signal "VCC")
		(20 "In9.Cu" signal "VCC1")
		(22 "In10.Cu" signal "GND4")
		(24 "In11.Cu" signal "IN4")
		(26 "In12.Cu" signal "GND5")
		(28 "In13.Cu" signal "IN5")
		(30 "In14.Cu" signal "GND6")
		(32 "In15.Cu" signal "IN6")
		(34 "In16.Cu" signal "GND7")
		(2 "B.Cu" signal "BOTTOM")
		(9 "F.Adhes" user "F.Adhesive")
		(11 "B.Adhes" user "B.Adhesive")
		(13 "F.Paste" user "Package Geometry/Pastemask Top")
		(15 "B.Paste" user "Package Geometry/Pastemask Bottom")
		(5 "F.SilkS" user "Ref Des/Silkscreen Top")
		(7 "B.SilkS" user "Ref Des/Silkscreen Bottom")
		(1 "F.Mask" user "Board Geometry/Soldermask Top")
		(3 "B.Mask" user "Board Geometry/Soldermask Bottom")
		(17 "Dwgs.User" user "User.Drawings")
		(19 "Cmts.User" user "User.Comments")
		(21 "Eco1.User" user "User.Eco1")
		(23 "Eco2.User" user "User.Eco2")
		(25 "Edge.Cuts" user "Board Geometry/Outline")
		(27 "Margin" user)
		(31 "F.CrtYd" user "Package Geometry/Place Bound Top")
		(29 "B.CrtYd" user "Package Geometry/Place Bound Bottom")
		(35 "F.Fab" user "Ref Des/Assembly Top")
		(33 "B.Fab" user "Ref Des/Assembly Bottom")
	)
	(footprint ""
		(layer "F.Cu")
		(at 351.666048 -339.93455)
		(property "Reference" "PU11"
			(at -1.527048 -8.01878 0)
			(unlocked yes)
			(layer "F.SilkS")
			(effects
				(font
					(size 0.7874 0.5842)
					(thickness 0.1524)
				)
				(justify left)
			)
		)
		(property "Value" ""
			(at 0 0 0)
			(layer "F.Fab")
			(effects
				(font
					(size 1.27 1.27)
				)
			)
		)
		(duplicate_pad_numbers_are_jumpers no)
		(fp_line
			(start -2.500122 -2.999994)
			(end -2.24409 -2.999994)
			(stroke
				(width 0.1524)
				(type default)
			)
			(layer "F.SilkS")
		)
		(fp_line
			(start -2.500122 -2.529078)
			(end -2.500122 -2.999994)
			(stroke
				(width 0.1524)
				(type default)
			)
			(layer "F.SilkS")
		)
		(fp_line
			(start -2.500122 0.6604)
			(end -2.500122 0.229108)
			(stroke
				(width 0.1524)
				(type default)
			)
			(layer "F.SilkS")
		)
		(fp_line
			(start -2.500122 2.999994)
			(end -2.500122 2.339594)
			(stroke
				(width 0.1524)
				(type default)
			)
			(layer "F.SilkS")
		)
		(fp_line
			(start -2.2987 2.999994)
			(end -2.500122 2.999994)
			(stroke
				(width 0.1524)
				(type default)
			)
			(layer "F.SilkS")
		)
		(fp_line
			(start 2.31394 -2.999994)
			(end 2.500122 -2.999994)
			(stroke
				(width 0.1524)
				(type default)
			)
			(layer "F.SilkS")
		)
		(fp_line
			(start 2.500122 -2.999994)
			(end 2.500122 -2.44348)
			(stroke
				(width 0.1524)
				(type default)
			)
			(layer "F.SilkS")
		)
		(fp_line
			(start 2.500122 2.339594)
			(end 2.500122 2.999994)
			(stroke
				(width 0.1524)
				(type default)
			)
			(layer "F.SilkS")
		)
		(fp_line
			(start 2.500122 2.999994)
			(end 2.2987 2.999994)
			(stroke
				(width 0.1524)
				(type default)
			)
			(layer "F.SilkS")
		)
		(fp_poly
			(pts
				(xy -2.765298 -2.448814) (xy -3.438906 -2.67335) (xy -2.989834 -3.122422)
			)
			(stroke
				(width 0)
				(type default)
			)
			(fill yes)
			(layer "F.SilkS")
		)
		(fp_line
			(start -2.500122 -2.999994)
			(end 2.500122 -2.999994)
			(stroke
				(width 0.1)
				(type default)
			)
			(layer "F.Fab")
		)
		(fp_line
			(start -2.500122 2.999994)
			(end -2.500122 -2.999994)
			(stroke
				(width 0.1)
				(type default)
			)
			(layer "F.Fab")
		)
		(fp_line
			(start 2.500122 -2.999994)
			(end 2.500122 2.999994)
			(stroke
				(width 0.1)
				(type default)
			)
			(layer "F.Fab")
		)
		(fp_line
			(start 2.500122 2.999994)
			(end -2.500122 2.999994)
			(stroke
				(width 0.1)
				(type default)
			)
			(layer "F.Fab")
		)
		(fp_poly
			(pts
				(xy -4.218432 -2.783078) (xy -4.218432 -1.767078) (xy -3.202432 -2.275078)
			)
			(stroke
				(width 0)
				(type default)
			)
			(fill yes)
			(layer "F.Fab")
		)
		(pad "1" smd rect
			(at -2.400046 -2.275078 90)
			(size 0.2286 0.6096)
			(layers "F.Cu" "F.Mask" "F.Paste")
			(net "PVDDCR_CPU1_P0_VOS6")
		)
		(pad "2" smd rect
			(at -2.400046 -1.82499 90)
			(size 0.2286 0.6096)
			(layers "F.Cu" "F.Mask" "F.Paste")
			(net "GND")
		)
		(pad "3" smd rect
			(at -2.400046 -1.374902 90)
			(size 0.2286 0.6096)
			(layers "F.Cu" "F.Mask" "F.Paste")
			(net "PVDDCR_CPU1_P0_VCC6")
		)
		(pad "4" smd rect
			(at -2.400046 -0.925068 90)
			(size 0.2286 0.6096)
			(layers "F.Cu" "F.Mask" "F.Paste")
			(net "PVDDCR_CPU1_P0_PVCC")
		)
		(pad "5" smd rect
			(at -2.400046 -0.47498 90)
			(size 0.2286 0.6096)
			(layers "F.Cu" "F.Mask" "F.Paste")
			(net "GND")
		)
		(pad "6" smd rect
			(at -2.400046 -0.024892 90)
			(size 0.2286 0.6096)
			(layers "F.Cu" "F.Mask" "F.Paste")
			(net "NC_PVDDCR_CPU1_P0_GL1_6")
		)
		(pad "7_9-20_24" smd circle
			(at 0 1.150112 90)
			(size 0 0)
			(layers "F.Cu" "F.Mask" "F.Paste")
			(net "GND")
		)
		(pad "10_19" smd rect
			(at 0 2.899918 90)
			(size 0.6096 4.318)
			(layers "F.Cu" "F.Mask" "F.Paste")
			(net "SW_PVDDCR_CPU1_P0_SW6")
		)
		(pad "25_29" smd rect
			(at 1.549908 -1.279906 270)
			(size 2.0574 2.3114)
			(layers "F.Cu" "F.Mask" "F.Paste")
			(net "SW_P12V_AUX_PVDDCR_CPU1_P0_FLT")
		)
		(pad "30" smd rect
			(at 2.05994 -2.899918)
			(size 0.2286 0.6096)
			(layers "F.Cu" "F.Mask" "F.Paste")
			(net "SW_P12V_AUX_PVDDCR_CPU1_P0_FLT")
		)
		(pad "31" smd rect
			(at 1.610106 -2.899918)
			(size 0.2286 0.6096)
			(layers "F.Cu" "F.Mask" "F.Paste")
			(net "NC_PVDDCR_CPU1_P0_DNC6")
		)
		(pad "32" smd rect
			(at 1.160018 -2.899918)
			(size 0.2286 0.6096)
			(layers "F.Cu" "F.Mask" "F.Paste")
			(net "SW_PVDDCR_CPU1_P0_BOOTR6")
		)
		(pad "33" smd rect
			(at 0.70993 -2.899918)
			(size 0.2286 0.6096)
			(layers "F.Cu" "F.Mask" "F.Paste")
			(net "SW_PVDDCR_CPU1_P0_BOOT6")
		)
		(pad "34" smd rect
			(at 0.260096 -2.899918)
			(size 0.2286 0.6096)
			(layers "F.Cu" "F.Mask" "F.Paste")
			(net "PVDDCR_CPU1_P0_PWM6")
		)
		(pad "35" smd rect
			(at -0.189992 -2.899918)
			(size 0.2286 0.6096)
			(layers "F.Cu" "F.Mask" "F.Paste")
			(net "PVDDCR_CPU1_P0_VCC6")
		)
		(pad "36" smd rect
			(at -0.64008 -2.899918)
			(size 0.2286 0.6096)
			(layers "F.Cu" "F.Mask" "F.Paste")
			(net "PVDDCR_CPU1_P0_TEMP0")
		)
		(pad "37" smd rect
			(at -1.089914 -2.899918)
			(size 0.2286 0.6096)
			(layers "F.Cu" "F.Mask" "F.Paste")
			(net "PVDDCR_CPU1_P0_LSET6")
		)
		(pad "38" smd rect
			(at -1.540002 -2.899918)
			(size 0.2286 0.6096)
			(layers "F.Cu" "F.Mask" "F.Paste")
			(net "PVDDCR_CPU1_P0_IMON6")
		)
		(pad "39" smd rect
			(at -1.99009 -2.899918)
			(size 0.2286 0.6096)
			(layers "F.Cu" "F.Mask" "F.Paste")
			(net "PVDDCR_CPU1_P0_VCCS")
		)
		(pad "40" smd rect
			(at -0.87503 -1.27508)
			(size 1.7526 1.9558)
			(layers "F.Cu" "F.Mask" "F.Paste")
			(net "GND")
		)
		(pad "41" smd rect
			(at -1.525016 0.249936 270)
			(size 0.3048 0.4572)
			(layers "F.Cu" "F.Mask" "F.Paste")
			(net "NC_PVDDCR_CPU1_P0_GL2_6")
		)
		(zone
			(layer "F.Cu")
			(hatch none 0.5)
			(connect_pads
				(clearance 0)
			)
			(min_thickness 0.25)
			(keepout
				(tracks not_allowed)
				(vias allowed)
				(pads allowed)
				(copperpour not_allowed)
				(footprints allowed)
			)
			(placement
				(enabled no)
				(sheetname "")
			)
			(fill
				(thermal_gap 0.5)
				(thermal_bridge_width 0.5)
				(island_removal_mode 0)
			)
			(polygon
				(pts
					(xy 349.165926 -337.354164) (xy 349.165926 -337.683856) (xy 354.16617 -337.683856) (xy 354.16617 -337.357212)
					(xy 353.875848 -337.357212) (xy 353.875848 -337.390232) (xy 349.456248 -337.390232) (xy 349.456248 -337.354164)
				)
			)
		)
		(zone
			(layer "F.Cu")
			(hatch none 0.5)
			(connect_pads
				(clearance 0)
			)
			(min_thickness 0.25)
			(keepout
				(tracks not_allowed)
				(vias allowed)
				(pads allowed)
				(copperpour not_allowed)
				(footprints allowed)
			)
			(placement
				(enabled no)
				(sheetname "")
			)
			(fill
				(thermal_gap 0.5)
				(thermal_bridge_width 0.5)
				(island_removal_mode 0)
			)
			(polygon
				(pts
					(xy 351.718118 -340.2203) (xy 351.718118 -342.23833) (xy 349.863918 -342.23833) (xy 349.863918 -341.997284)
					(xy 349.621602 -341.997284) (xy 349.621602 -342.478868) (xy 353.40671 -342.478868) (xy 353.40671 -342.293956)
					(xy 352.009456 -342.293956) (xy 352.009456 -340.134956) (xy 354.16617 -340.134956) (xy 354.16617 -339.885274)
					(xy 352.053144 -339.885274)
				)
			)
		)
	)
)
